# T6G (Grand Teton) — schematic netlist excerpt (pin names and nets, part order shuffled) for the footprints in the layout excerpt that follows; sources: Cadence DE-HDL packaged netlist, KiCad conversion of 04192023_DAF0TMB3IC0_F0TG_MB_C_brd_V02_OCP.brd

U116  SN74AVC4T774PWR  IC  pkg TSSOP16XC  page 164
  DIR1  = PVDD18_S5_P0
  DIR2  = GND
  A1  = UART_CPU0_SCM_UART1_TX
  A2  = UART_CPU0_SCM_UART1_R_RX
  A3  = UART_CPU0_UART0_TX
  A4  = UART_CPU0_UART0_R_RX
  DIR3  = PVDD18_S5_P0
  DIR4  = GND
  OE  = UART_LS_EN_N
  GND  = GND
  B4  = UART_CPU0_LVC3_UART0_R_RX
  B3  = UART_CPU0_LVC3_UART0_R_TX
  B2  = UART_CPU0_SCM_LVC3_UART1_R_RX
  B1  = UART_CPU0_SCM_LVC3_UART1_R_TX
  VCCB  = P3V3_AUX
  VCCA  = PVDD18_S5_P0

R1145  Q_RES  10K 5% EMPTY  pkg 0402LF  page 136 : A = P3V3_AUX ; B = OCP_SFF_AUX_PWR_EN

(kicad_pcb
	(version 20260206)
	(generator "pcbnew")
	(generator_version "10.0")
	(general
		(thickness 1.6)
		(legacy_teardrops no)
	)
	(paper "A4")
	(title_block
		(title "04192023_DAF0TMB3IC0_F0TG_MB_C_brd_V02_OCP.brd")
		(comment 1 "Grand Teton / footprints 4382-4383 of 8354")
	)
	(layers
		(0 "F.Cu" signal "TOP")
		(4 "In1.Cu" signal "GND")
		(6 "In2.Cu" signal "IN1")
		(8 "In3.Cu" signal "GND1")
		(10 "In4.Cu" signal "IN2")
		(12 "In5.Cu" signal "GND2")
		(14 "In6.Cu" signal "IN3")
		(16 "In7.Cu" signal "GND3")
		(18 "In8.Cu" signal "VCC")
		(20 "In9.Cu" signal "VCC1")
		(22 "In10.Cu" signal "GND4")
		(24 "In11.Cu" signal "IN4")
		(26 "In12.Cu" signal "GND5")
		(28 "In13.Cu" signal "IN5")
		(30 "In14.Cu" signal "GND6")
		(32 "In15.Cu" signal "IN6")
		(34 "In16.Cu" signal "GND7")
		(2 "B.Cu" signal "BOTTOM")
		(9 "F.Adhes" user "F.Adhesive")
		(11 "B.Adhes" user "B.Adhesive")
		(13 "F.Paste" user "Package Geometry/Pastemask Top")
		(15 "B.Paste" user "Package Geometry/Pastemask Bottom")
		(5 "F.SilkS" user "Ref Des/Silkscreen Top")
		(7 "B.SilkS" user "Ref Des/Silkscreen Bottom")
		(1 "F.Mask" user "Board Geometry/Soldermask Top")
		(3 "B.Mask" user "Board Geometry/Soldermask Bottom")
		(17 "Dwgs.User" user "User.Drawings")
		(19 "Cmts.User" user "User.Comments")
		(21 "Eco1.User" user "User.Eco1")
		(23 "Eco2.User" user "User.Eco2")
		(25 "Edge.Cuts" user "Board Geometry/Outline")
		(27 "Margin" user)
		(31 "F.CrtYd" user "Package Geometry/Place Bound Top")
		(29 "B.CrtYd" user "Package Geometry/Place Bound Bottom")
		(35 "F.Fab" user "Ref Des/Assembly Top")
		(33 "B.Fab" user "Ref Des/Assembly Bottom")
	)
	(footprint ""
		(layer "F.Cu")
		(at 367.606326 -37.043868 -90)
		(property "Reference" "U116"
			(at 0.449834 -3.882136 90)
			(unlocked yes)
			(layer "F.SilkS")
			(effects
				(font
					(size 0.7874 0.5842)
					(thickness 0.1524)
				)
				(justify left)
			)
		)
		(property "Value" ""
			(at 0 0 270)
			(layer "F.Fab")
			(effects
				(font
					(size 1.27 1.27)
				)
			)
		)
		(duplicate_pad_numbers_are_jumpers no)
		(fp_line
			(start -1.868932 2.549906)
			(end 1.868932 2.549906)
			(stroke
				(width 0.1524)
				(type default)
			)
			(layer "F.SilkS")
		)
		(fp_line
			(start 1.868932 2.549906)
			(end 1.868932 -2.549906)
			(stroke
				(width 0.1524)
				(type default)
			)
			(layer "F.SilkS")
		)
		(fp_line
			(start 0 -1.524)
			(end -1.025906 -2.549906)
			(stroke
				(width 0.1524)
				(type default)
			)
			(layer "F.SilkS")
		)
		(fp_line
			(start -1.868932 -2.549906)
			(end -1.868932 2.549906)
			(stroke
				(width 0.1524)
				(type default)
			)
			(layer "F.SilkS")
		)
		(fp_line
			(start -1.025906 -2.549906)
			(end -1.868932 -2.549906)
			(stroke
				(width 0.1524)
				(type default)
			)
			(layer "F.SilkS")
		)
		(fp_line
			(start 1.025906 -2.549906)
			(end 0 -1.524)
			(stroke
				(width 0.1524)
				(type default)
			)
			(layer "F.SilkS")
		)
		(fp_line
			(start 1.868932 -2.549906)
			(end 1.025906 -2.549906)
			(stroke
				(width 0.1524)
				(type default)
			)
			(layer "F.SilkS")
		)
		(fp_poly
			(pts
				(xy -4.240276 -2.43078) (xy -5.256276 -1.92278) (xy -5.256276 -2.93878)
			)
			(stroke
				(width 0)
				(type default)
			)
			(fill yes)
			(layer "F.SilkS")
		)
		(fp_line
			(start -2.249932 2.549906)
			(end 2.249932 2.549906)
			(stroke
				(width 0.1)
				(type default)
			)
			(layer "F.Fab")
		)
		(fp_line
			(start 2.249932 2.549906)
			(end 2.249932 -2.549906)
			(stroke
				(width 0.1)
				(type default)
			)
			(layer "F.Fab")
		)
		(fp_line
			(start -2.249932 -2.549906)
			(end -2.249932 2.549906)
			(stroke
				(width 0.1)
				(type default)
			)
			(layer "F.Fab")
		)
		(fp_line
			(start 2.249932 -2.549906)
			(end -2.249932 -2.549906)
			(stroke
				(width 0.1)
				(type default)
			)
			(layer "F.Fab")
		)
		(fp_poly
			(pts
				(xy -4.7752 -1.787398) (xy -4.7752 -2.803398) (xy -3.7592 -2.295398)
			)
			(stroke
				(width 0)
				(type default)
			)
			(fill yes)
			(layer "F.Fab")
		)
		(pad "1" smd rect
			(at -2.800096 -2.275078 180)
			(size 0.3556 1.6002)
			(layers "F.Cu" "F.Mask" "F.Paste")
			(net "PVDD18_S5_P0")
		)
		(pad "2" smd rect
			(at -2.800096 -1.625092 180)
			(size 0.3556 1.6002)
			(layers "F.Cu" "F.Mask" "F.Paste")
			(net "GND")
		)
		(pad "3" smd rect
			(at -2.800096 -0.975106 180)
			(size 0.3556 1.6002)
			(layers "F.Cu" "F.Mask" "F.Paste")
			(net "UART_CPU0_SCM_UART1_TX")
		)
		(pad "4" smd rect
			(at -2.800096 -0.32512 180)
			(size 0.3556 1.6002)
			(layers "F.Cu" "F.Mask" "F.Paste")
			(net "UART_CPU0_SCM_UART1_R_RX")
		)
		(pad "5" smd rect
			(at -2.800096 0.32512 180)
			(size 0.3556 1.6002)
			(layers "F.Cu" "F.Mask" "F.Paste")
			(net "UART_CPU0_UART0_TX")
		)
		(pad "6" smd rect
			(at -2.800096 0.975106 180)
			(size 0.3556 1.6002)
			(layers "F.Cu" "F.Mask" "F.Paste")
			(net "UART_CPU0_UART0_R_RX")
		)
		(pad "7" smd rect
			(at -2.800096 1.625092 180)
			(size 0.3556 1.6002)
			(layers "F.Cu" "F.Mask" "F.Paste")
			(net "PVDD18_S5_P0")
		)
		(pad "8" smd rect
			(at -2.800096 2.275078 180)
			(size 0.3556 1.6002)
			(layers "F.Cu" "F.Mask" "F.Paste")
			(net "GND")
		)
		(pad "9" smd rect
			(at 2.800096 2.275078 180)
			(size 0.3556 1.6002)
			(layers "F.Cu" "F.Mask" "F.Paste")
			(net "UART_LS_EN_N")
		)
		(pad "10" smd rect
			(at 2.800096 1.625092 180)
			(size 0.3556 1.6002)
			(layers "F.Cu" "F.Mask" "F.Paste")
			(net "GND")
		)
		(pad "11" smd rect
			(at 2.800096 0.975106 180)
			(size 0.3556 1.6002)
			(layers "F.Cu" "F.Mask" "F.Paste")
			(net "UART_CPU0_LVC3_UART0_R_RX")
		)
		(pad "12" smd rect
			(at 2.800096 0.32512 180)
			(size 0.3556 1.6002)
			(layers "F.Cu" "F.Mask" "F.Paste")
			(net "UART_CPU0_LVC3_UART0_R_TX")
		)
		(pad "13" smd rect
			(at 2.800096 -0.32512 180)
			(size 0.3556 1.6002)
			(layers "F.Cu" "F.Mask" "F.Paste")
			(net "UART_CPU0_SCM_LVC3_UART1_R_RX")
		)
		(pad "14" smd rect
			(at 2.800096 -0.975106 180)
			(size 0.3556 1.6002)
			(layers "F.Cu" "F.Mask" "F.Paste")
			(net "UART_CPU0_SCM_LVC3_UART1_R_TX")
		)
		(pad "15" smd rect
			(at 2.800096 -1.625092 180)
			(size 0.3556 1.6002)
			(layers "F.Cu" "F.Mask" "F.Paste")
			(net "P3V3_AUX")
		)
		(pad "16" smd rect
			(at 2.800096 -2.275078 180)
			(size 0.3556 1.6002)
			(layers "F.Cu" "F.Mask" "F.Paste")
			(net "PVDD18_S5_P0")
		)
	)
	(footprint ""
		(layer "F.Cu")
		(at 215.9 -96.774 180)
		(property "Reference" "R1145"
			(at 0 0 180)
			(layer "F.SilkS")
			(hide yes)
			(effects
				(font
					(size 1.27 1.27)
				)
			)
		)
		(property "Value" ""
			(at 0 0 180)
			(layer "F.Fab")
			(effects
				(font
					(size 1.27 1.27)
				)
			)
		)
		(duplicate_pad_numbers_are_jumpers no)
		(fp_line
			(start 0.7874 0.4064)
			(end -0.7874 0.4064)
			(stroke
				(width 0.1524)
				(type default)
			)
			(layer "F.SilkS")
		)
		(fp_line
			(start 0.7874 -0.4064)
			(end 0.7874 0.4064)
			(stroke
				(width 0.1524)
				(type default)
			)
			(layer "F.SilkS")
		)
		(fp_line
			(start -0.7874 0.4064)
			(end -0.7874 -0.4064)
			(stroke
				(width 0.1524)
				(type default)
			)
			(layer "F.SilkS")
		)
		(fp_line
			(start -0.7874 -0.4064)
			(end 0.7874 -0.4064)
			(stroke
				(width 0.1524)
				(type default)
			)
			(layer "F.SilkS")
		)
		(fp_line
			(start 0.67945 0.3048)
			(end 0.120396 0.3048)
			(stroke
				(width 0.1)
				(type default)
			)
			(layer "F.Fab")
		)
		(fp_line
			(start 0.67945 -0.3048)
			(end 0.67945 0.3048)
			(stroke
				(width 0.1)
				(type default)
			)
			(layer "F.Fab")
		)
		(fp_line
			(start 0.12065 -0.2794)
			(end 0.12065 -0.3048)
			(stroke
				(width 0.1)
				(type default)
			)
			(layer "F.Fab")
		)
		(fp_line
			(start 0.12065 -0.3048)
			(end 0.67945 -0.3048)
			(stroke
				(width 0.1)
				(type default)
			)
			(layer "F.Fab")
		)
		(fp_line
			(start 0.120396 0.3048)
			(end 0.120396 0.2794)
			(stroke
				(width 0.1)
				(type default)
			)
			(layer "F.Fab")
		)
		(fp_line
			(start 0.120396 0.2794)
			(end -0.12065 0.2794)
			(stroke
				(width 0.1)
				(type default)
			)
			(layer "F.Fab")
		)
		(fp_line
			(start -0.12065 0.3048)
			(end -0.67945 0.3048)
			(stroke
				(width 0.1)
				(type default)
			)
			(layer "F.Fab")
		)
		(fp_line
			(start -0.12065 0.2794)
			(end -0.12065 0.3048)
			(stroke
				(width 0.1)
				(type default)
			)
			(layer "F.Fab")
		)
		(fp_line
			(start -0.12065 -0.2794)
			(end 0.12065 -0.2794)
			(stroke
				(width 0.1)
				(type default)
			)
			(layer "F.Fab")
		)
		(fp_line
			(start -0.12065 -0.305054)
			(end -0.12065 -0.2794)
			(stroke
				(width 0.1)
				(type default)
			)
			(layer "F.Fab")
		)
		(fp_line
			(start -0.67945 0.3048)
			(end -0.67945 -0.305054)
			(stroke
				(width 0.1)
				(type default)
			)
			(layer "F.Fab")
		)
		(fp_line
			(start -0.67945 -0.305054)
			(end -0.12065 -0.305054)
			(stroke
				(width 0.1)
				(type default)
			)
			(layer "F.Fab")
		)
		(pad "1" smd circle
			(at -0.40005 0 180)
			(size 0 0)
			(layers "F.Cu" "F.Mask" "F.Paste")
			(net "P3V3_AUX")
		)
		(pad "2" smd circle
			(at 0.40005 0 180)
			(size 0 0)
			(layers "F.Cu" "F.Mask" "F.Paste")
			(net "OCP_SFF_AUX_PWR_EN")
		)
	)
)
